(kicad_pcb
	(version 20260206)
	(generator "pcbnew")
	(generator_version "10.0")
	(general
		(thickness 1.6)
		(legacy_teardrops no)
	)
	(paper "A4")
	(title_block
		(title "04192023_DAF0TMB3IC0_F0TG_MB_C_brd_V02_OCP.brd")
		(comment 1 "Grand Teton / footprints 1095-1099 of 8354")
	)
	(layers
		(0 "F.Cu" signal "TOP")
		(4 "In1.Cu" signal "GND")
		(6 "In2.Cu" signal "IN1")
		(8 "In3.Cu" signal "GND1")
		(10 "In4.Cu" signal "IN2")
		(12 "In5.Cu" signal "GND2")
		(14 "In6.Cu" signal "IN3")
		(16 "In7.Cu" signal "GND3")
		(18 "In8.Cu" signal "VCC")
		(20 "In9.Cu" signal "VCC1")
		(22 "In10.Cu" signal "GND4")
		(24 "In11.Cu" signal "IN4")
		(26 "In12.Cu" signal "GND5")
		(28 "In13.Cu" signal "IN5")
		(30 "In14.Cu" signal "GND6")
		(32 "In15.Cu" signal "IN6")
		(34 "In16.Cu" signal "GND7")
		(2 "B.Cu" signal "BOTTOM")
		(9 "F.Adhes" user "F.Adhesive")
		(11 "B.Adhes" user "B.Adhesive")
		(13 "F.Paste" user "Package Geometry/Pastemask Top")
		(15 "B.Paste" user "Package Geometry/Pastemask Bottom")
		(5 "F.SilkS" user "Ref Des/Silkscreen Top")
		(7 "B.SilkS" user "Ref Des/Silkscreen Bottom")
		(1 "F.Mask" user "Board Geometry/Soldermask Top")
		(3 "B.Mask" user "Board Geometry/Soldermask Bottom")
		(17 "Dwgs.User" user "User.Drawings")
		(19 "Cmts.User" user "User.Comments")
		(21 "Eco1.User" user "User.Eco1")
		(23 "Eco2.User" user "User.Eco2")
		(25 "Edge.Cuts" user "Board Geometry/Outline")
		(27 "Margin" user)
		(31 "F.CrtYd" user "Package Geometry/Place Bound Top")
		(29 "B.CrtYd" user "Package Geometry/Place Bound Bottom")
		(35 "F.Fab" user "Ref Des/Assembly Top")
		(33 "B.Fab" user "Ref Des/Assembly Bottom")
	)
	(footprint ""
		(layer "F.Cu")
		(at 45.71492 -111.32058 180)
		(property "Reference" "R1475"
			(at 0 0 180)
			(layer "F.SilkS")
			(hide yes)
			(effects
				(font
					(size 1.27 1.27)
				)
			)
		)
		(property "Value" ""
			(at 0 0 180)
			(layer "F.Fab")
			(effects
				(font
					(size 1.27 1.27)
				)
			)
		)
		(duplicate_pad_numbers_are_jumpers no)
		(fp_line
			(start 0.7874 0.4064)
			(end -0.7874 0.4064)
			(stroke
				(width 0.1524)
				(type default)
			)
			(layer "F.SilkS")
		)
		(fp_line
			(start 0.7874 -0.4064)
			(end 0.7874 0.4064)
			(stroke
				(width 0.1524)
				(type default)
			)
			(layer "F.SilkS")
		)
		(fp_line
			(start -0.7874 0.4064)
			(end -0.7874 -0.4064)
			(stroke
				(width 0.1524)
				(type default)
			)
			(layer "F.SilkS")
		)
		(fp_line
			(start -0.7874 -0.4064)
			(end 0.7874 -0.4064)
			(stroke
				(width 0.1524)
				(type default)
			)
			(layer "F.SilkS")
		)
		(fp_line
			(start 0.67945 0.3048)
			(end 0.120396 0.3048)
			(stroke
				(width 0.1)
				(type default)
			)
			(layer "F.Fab")
		)
		(fp_line
			(start 0.67945 -0.3048)
			(end 0.67945 0.3048)
			(stroke
				(width 0.1)
				(type default)
			)
			(layer "F.Fab")
		)
		(fp_line
			(start 0.12065 -0.2794)
			(end 0.12065 -0.3048)
			(stroke
				(width 0.1)
				(type default)
			)
			(layer "F.Fab")
		)
		(fp_line
			(start 0.12065 -0.3048)
			(end 0.67945 -0.3048)
			(stroke
				(width 0.1)
				(type default)
			)
			(layer "F.Fab")
		)
		(fp_line
			(start 0.120396 0.3048)
			(end 0.120396 0.2794)
			(stroke
				(width 0.1)
				(type default)
			)
			(layer "F.Fab")
		)
		(fp_line
			(start 0.120396 0.2794)
			(end -0.12065 0.2794)
			(stroke
				(width 0.1)
				(type default)
			)
			(layer "F.Fab")
		)
		(fp_line
			(start -0.12065 0.3048)
			(end -0.67945 0.3048)
			(stroke
				(width 0.1)
				(type default)
			)
			(layer "F.Fab")
		)
		(fp_line
			(start -0.12065 0.2794)
			(end -0.12065 0.3048)
			(stroke
				(width 0.1)
				(type default)
			)
			(layer "F.Fab")
		)
		(fp_line
			(start -0.12065 -0.2794)
			(end 0.12065 -0.2794)
			(stroke
				(width 0.1)
				(type default)
			)
			(layer "F.Fab")
		)
		(fp_line
			(start -0.12065 -0.305054)
			(end -0.12065 -0.2794)
			(stroke
				(width 0.1)
				(type default)
			)
			(layer "F.Fab")
		)
		(fp_line
			(start -0.67945 0.3048)
			(end -0.67945 -0.305054)
			(stroke
				(width 0.1)
				(type default)
			)
			(layer "F.Fab")
		)
		(fp_line
			(start -0.67945 -0.305054)
			(end -0.12065 -0.305054)
			(stroke
				(width 0.1)
				(type default)
			)
			(layer "F.Fab")
		)
		(pad "1" smd circle
			(at -0.40005 0 180)
			(size 0 0)
			(layers "F.Cu" "F.Mask" "F.Paste")
			(net "P3V3_AUX_DSC_G2")
		)
		(pad "2" smd circle
			(at 0.40005 0 180)
			(size 0 0)
			(layers "F.Cu" "F.Mask" "F.Paste")
			(net "GND")
		)
	)
	(footprint ""
		(layer "F.Cu")
		(at 425.36872 -388.767828)
		(property "Reference" "C838"
			(at 0 0 0)
			(layer "F.SilkS")
			(hide yes)
			(effects
				(font
					(size 1.27 1.27)
				)
			)
		)
		(property "Value" ""
			(at 0 0 0)
			(layer "F.Fab")
			(effects
				(font
					(size 1.27 1.27)
				)
			)
		)
		(duplicate_pad_numbers_are_jumpers no)
		(fp_line
			(start -0.299974 -0.150114)
			(end 0.299974 -0.150114)
			(stroke
				(width 0.1)
				(type default)
			)
			(layer "F.Fab")
		)
		(fp_line
			(start -0.299974 0.150114)
			(end -0.299974 -0.150114)
			(stroke
				(width 0.1)
				(type default)
			)
			(layer "F.Fab")
		)
		(fp_line
			(start 0.299974 -0.150114)
			(end 0.299974 0.150114)
			(stroke
				(width 0.1)
				(type default)
			)
			(layer "F.Fab")
		)
		(fp_line
			(start 0.299974 0.150114)
			(end -0.299974 0.150114)
			(stroke
				(width 0.1)
				(type default)
			)
			(layer "F.Fab")
		)
		(pad "1" smd rect
			(at -0.2667 0)
			(size 0.3048 0.381)
			(layers "F.Cu" "F.Mask" "F.Paste")
			(net "P5E_CPU0_P2_TX_C_DN<15>")
		)
		(pad "2" smd rect
			(at 0.2667 0)
			(size 0.3048 0.381)
			(layers "F.Cu" "F.Mask" "F.Paste")
			(net "P5E_CPU0_P2_TX_DN<15>")
		)
	)
	(footprint ""
		(layer "F.Cu")
		(at 264.174986 -119.207026)
		(property "Reference" "U39"
			(at -2.482342 -5.187696 0)
			(unlocked yes)
			(layer "F.SilkS")
			(effects
				(font
					(size 0.7874 0.5842)
					(thickness 0.1524)
				)
				(justify left)
			)
		)
		(property "Value" ""
			(at 0 0 0)
			(layer "F.Fab")
			(effects
				(font
					(size 1.27 1.27)
				)
			)
		)
		(duplicate_pad_numbers_are_jumpers no)
		(fp_line
			(start -1.8542 -3.949954)
			(end -1.8542 3.949954)
			(stroke
				(width 0.1524)
				(type default)
			)
			(layer "F.SilkS")
		)
		(fp_line
			(start -1.8542 3.949954)
			(end 1.8542 3.949954)
			(stroke
				(width 0.1524)
				(type default)
			)
			(layer "F.SilkS")
		)
		(fp_line
			(start -1.282954 -3.949954)
			(end -1.8542 -3.949954)
			(stroke
				(width 0.1524)
				(type default)
			)
			(layer "F.SilkS")
		)
		(fp_line
			(start 0 -2.667)
			(end -1.282954 -3.949954)
			(stroke
				(width 0.1524)
				(type default)
			)
			(layer "F.SilkS")
		)
		(fp_line
			(start 1.282954 -3.949954)
			(end 0 -2.667)
			(stroke
				(width 0.1524)
				(type default)
			)
			(layer "F.SilkS")
		)
		(fp_line
			(start 1.8542 -3.949954)
			(end 1.282954 -3.949954)
			(stroke
				(width 0.1524)
				(type default)
			)
			(layer "F.SilkS")
		)
		(fp_line
			(start 1.8542 3.949954)
			(end 1.8542 -3.949954)
			(stroke
				(width 0.1524)
				(type default)
			)
			(layer "F.SilkS")
		)
		(fp_poly
			(pts
				(xy -3.7846 -3.57505) (xy -4.8006 -3.06705) (xy -4.8006 -4.08305)
			)
			(stroke
				(width 0)
				(type default)
			)
			(fill yes)
			(layer "F.SilkS")
		)
		(fp_line
			(start -2.249932 -3.949954)
			(end -2.249932 3.949954)
			(stroke
				(width 0.1)
				(type default)
			)
			(layer "F.Fab")
		)
		(fp_line
			(start -2.249932 3.949954)
			(end 2.249932 3.949954)
			(stroke
				(width 0.1)
				(type default)
			)
			(layer "F.Fab")
		)
		(fp_line
			(start 2.249932 -3.949954)
			(end -2.249932 -3.949954)
			(stroke
				(width 0.1)
				(type default)
			)
			(layer "F.Fab")
		)
		(fp_line
			(start 2.249932 3.949954)
			(end 2.249932 -3.949954)
			(stroke
				(width 0.1)
				(type default)
			)
			(layer "F.Fab")
		)
		(fp_poly
			(pts
				(xy -4.8006 -4.08305) (xy -4.8006 -3.06705) (xy -3.7846 -3.57505)
			)
			(stroke
				(width 0)
				(type default)
			)
			(fill yes)
			(layer "F.Fab")
		)
		(pad "1" smd rect
			(at -2.800096 -3.57505 270)
			(size 0.3048 1.6002)
			(layers "F.Cu" "F.Mask" "F.Paste")
			(net "PCA9548_PCIE0_ADDR0")
		)
		(pad "2" smd rect
			(at -2.800096 -2.925064 270)
			(size 0.3048 1.6002)
			(layers "F.Cu" "F.Mask" "F.Paste")
			(net "PCA9548_PCIE0_ADDR1")
		)
		(pad "3" smd rect
			(at -2.800096 -2.275078 270)
			(size 0.3048 1.6002)
			(layers "F.Cu" "F.Mask" "F.Paste")
			(net "PU_RST_SMB_PCIE2_N")
		)
		(pad "4" smd rect
			(at -2.800096 -1.625092 270)
			(size 0.3048 1.6002)
			(layers "F.Cu" "F.Mask" "F.Paste")
			(net "SMB_VR_3V3AUX_SDA_R6")
		)
		(pad "5" smd rect
			(at -2.800096 -0.975106 270)
			(size 0.3048 1.6002)
			(layers "F.Cu" "F.Mask" "F.Paste")
			(net "SMB_VR_3V3AUX_SCL_R6")
		)
		(pad "6" smd rect
			(at -2.800096 -0.32512 270)
			(size 0.3048 1.6002)
			(layers "F.Cu" "F.Mask" "F.Paste")
			(net "SMB_LM75_0_3V3AUX_SDA_R")
		)
		(pad "7" smd rect
			(at -2.800096 0.32512 270)
			(size 0.3048 1.6002)
			(layers "F.Cu" "F.Mask" "F.Paste")
			(net "SMB_LM75_0_3V3AUX_SCL_R")
		)
		(pad "8" smd rect
			(at -2.800096 0.975106 270)
			(size 0.3048 1.6002)
			(layers "F.Cu" "F.Mask" "F.Paste")
			(net "SMB_LM75_1_3V3AUX_SDA_R")
		)
		(pad "9" smd rect
			(at -2.800096 1.625092 270)
			(size 0.3048 1.6002)
			(layers "F.Cu" "F.Mask" "F.Paste")
			(net "SMB_LM75_1_3V3AUX_SCL_R")
		)
		(pad "10" smd rect
			(at -2.800096 2.275078 270)
			(size 0.3048 1.6002)
			(layers "F.Cu" "F.Mask" "F.Paste")
			(net "SMB_LM75_2_3V3AUX_SDA_R")
		)
		(pad "11" smd rect
			(at -2.800096 2.925064 270)
			(size 0.3048 1.6002)
			(layers "F.Cu" "F.Mask" "F.Paste")
			(net "SMB_LM75_2_3V3AUX_SCL_R")
		)
		(pad "12" smd rect
			(at -2.800096 3.57505 270)
			(size 0.3048 1.6002)
			(layers "F.Cu" "F.Mask" "F.Paste")
			(net "GND")
		)
		(pad "13" smd rect
			(at 2.800096 3.57505 270)
			(size 0.3048 1.6002)
			(layers "F.Cu" "F.Mask" "F.Paste")
			(net "SMB_LM75_3_3V3AUX_SDA_R")
		)
		(pad "14" smd rect
			(at 2.800096 2.925064 270)
			(size 0.3048 1.6002)
			(layers "F.Cu" "F.Mask" "F.Paste")
			(net "SMB_LM75_3_3V3AUX_SCL_R")
		)
		(pad "15" smd rect
			(at 2.800096 2.275078 270)
			(size 0.3048 1.6002)
			(layers "F.Cu" "F.Mask" "F.Paste")
			(net "SMB_P12V_HSC_SDA_R")
		)
		(pad "16" smd rect
			(at 2.800096 1.625092 270)
			(size 0.3048 1.6002)
			(layers "F.Cu" "F.Mask" "F.Paste")
			(net "SMB_P12V_HSC_SCL_R")
		)
		(pad "17" smd rect
			(at 2.800096 0.975106 270)
			(size 0.3048 1.6002)
			(layers "F.Cu" "F.Mask" "F.Paste")
			(net "SMB_ADC_SDA")
		)
		(pad "18" smd rect
			(at 2.800096 0.32512 270)
			(size 0.3048 1.6002)
			(layers "F.Cu" "F.Mask" "F.Paste")
			(net "SMB_ADC_SCL")
		)
		(pad "19" smd rect
			(at 2.800096 -0.32512 270)
			(size 0.3048 1.6002)
			(layers "F.Cu" "F.Mask" "F.Paste")
			(net "Net_10755")
		)
		(pad "20" smd rect
			(at 2.800096 -0.975106 270)
			(size 0.3048 1.6002)
			(layers "F.Cu" "F.Mask" "F.Paste")
			(net "Net_10756")
		)
		(pad "21" smd rect
			(at 2.800096 -1.625092 270)
			(size 0.3048 1.6002)
			(layers "F.Cu" "F.Mask" "F.Paste")
			(net "PCA9548_PCIE0_ADDR2")
		)
		(pad "22" smd rect
			(at 2.800096 -2.275078 270)
			(size 0.3048 1.6002)
			(layers "F.Cu" "F.Mask" "F.Paste")
			(net "SMB_VR_SENSOR_3V3AUX_SCL_R")
		)
		(pad "23" smd rect
			(at 2.800096 -2.925064 270)
			(size 0.3048 1.6002)
			(layers "F.Cu" "F.Mask" "F.Paste")
			(net "SMB_VR_SENSOR_3V3AUX_SDA_R")
		)
		(pad "24" smd rect
			(at 2.800096 -3.57505 270)
			(size 0.3048 1.6002)
			(layers "F.Cu" "F.Mask" "F.Paste")
			(net "P3V3_AUX")
		)
	)
	(footprint ""
		(layer "F.Cu")
		(at 16.645382 -104.76611 90)
		(property "Reference" "R3652"
			(at 0 0 90)
			(layer "F.SilkS")
			(hide yes)
			(effects
				(font
					(size 1.27 1.27)
				)
			)
		)
		(property "Value" ""
			(at 0 0 90)
			(layer "F.Fab")
			(effects
				(font
					(size 1.27 1.27)
				)
			)
		)
		(duplicate_pad_numbers_are_jumpers no)
		(fp_line
			(start 0.7874 -0.4064)
			(end 0.7874 0.4064)
			(stroke
				(width 0.1524)
				(type default)
			)
			(layer "F.SilkS")
		)
		(fp_line
			(start -0.7874 -0.4064)
			(end 0.7874 -0.4064)
			(stroke
				(width 0.1524)
				(type default)
			)
			(layer "F.SilkS")
		)
		(fp_line
			(start 0.7874 0.4064)
			(end -0.7874 0.4064)
			(stroke
				(width 0.1524)
				(type default)
			)
			(layer "F.SilkS")
		)
		(fp_line
			(start -0.7874 0.4064)
			(end -0.7874 -0.4064)
			(stroke
				(width 0.1524)
				(type default)
			)
			(layer "F.SilkS")
		)
		(fp_line
			(start -0.12065 -0.305054)
			(end -0.12065 -0.2794)
			(stroke
				(width 0.1)
				(type default)
			)
			(layer "F.Fab")
		)
		(fp_line
			(start -0.67945 -0.305054)
			(end -0.12065 -0.305054)
			(stroke
				(width 0.1)
				(type default)
			)
			(layer "F.Fab")
		)
		(fp_line
			(start 0.67945 -0.3048)
			(end 0.67945 0.3048)
			(stroke
				(width 0.1)
				(type default)
			)
			(layer "F.Fab")
		)
		(fp_line
			(start 0.12065 -0.3048)
			(end 0.67945 -0.3048)
			(stroke
				(width 0.1)
				(type default)
			)
			(layer "F.Fab")
		)
		(fp_line
			(start 0.12065 -0.2794)
			(end 0.12065 -0.3048)
			(stroke
				(width 0.1)
				(type default)
			)
			(layer "F.Fab")
		)
		(fp_line
			(start -0.12065 -0.2794)
			(end 0.12065 -0.2794)
			(stroke
				(width 0.1)
				(type default)
			)
			(layer "F.Fab")
		)
		(fp_line
			(start 0.120396 0.2794)
			(end -0.12065 0.2794)
			(stroke
				(width 0.1)
				(type default)
			)
			(layer "F.Fab")
		)
		(fp_line
			(start -0.12065 0.2794)
			(end -0.12065 0.3048)
			(stroke
				(width 0.1)
				(type default)
			)
			(layer "F.Fab")
		)
		(fp_line
			(start 0.67945 0.3048)
			(end 0.120396 0.3048)
			(stroke
				(width 0.1)
				(type default)
			)
			(layer "F.Fab")
		)
		(fp_line
			(start 0.120396 0.3048)
			(end 0.120396 0.2794)
			(stroke
				(width 0.1)
				(type default)
			)
			(layer "F.Fab")
		)
		(fp_line
			(start -0.12065 0.3048)
			(end -0.67945 0.3048)
			(stroke
				(width 0.1)
				(type default)
			)
			(layer "F.Fab")
		)
		(fp_line
			(start -0.67945 0.3048)
			(end -0.67945 -0.305054)
			(stroke
				(width 0.1)
				(type default)
			)
			(layer "F.Fab")
		)
		(pad "1" smd rect
			(at -0.40005 0 270)
			(size 0.4572 0.508)
			(layers "F.Cu" "F.Mask" "F.Paste")
			(net "USB2_P0_R_DN")
		)
		(pad "2" smd rect
			(at 0.40005 0 270)
			(size 0.4572 0.508)
			(layers "F.Cu" "F.Mask" "F.Paste")
			(net "USB2_HOST_BMC_B_DN")
		)
	)
	(footprint ""
		(layer "F.Cu")
		(at 124.459238 -41.17975 90)
		(property "Reference" "R6275"
			(at 0 0 90)
			(layer "F.SilkS")
			(hide yes)
			(effects
				(font
					(size 1.27 1.27)
				)
			)
		)
		(property "Value" ""
			(at 0 0 90)
			(layer "F.Fab")
			(effects
				(font
					(size 1.27 1.27)
				)
			)
		)
		(duplicate_pad_numbers_are_jumpers no)
		(fp_line
			(start 0.7874 -0.4064)
			(end 0.7874 0.4064)
			(stroke
				(width 0.1524)
				(type default)
			)
			(layer "F.SilkS")
		)
		(fp_line
			(start -0.7874 -0.4064)
			(end 0.7874 -0.4064)
			(stroke
				(width 0.1524)
				(type default)
			)
			(layer "F.SilkS")
		)
		(fp_line
			(start 0.7874 0.4064)
			(end -0.7874 0.4064)
			(stroke
				(width 0.1524)
				(type default)
			)
			(layer "F.SilkS")
		)
		(fp_line
			(start -0.7874 0.4064)
			(end -0.7874 -0.4064)
			(stroke
				(width 0.1524)
				(type default)
			)
			(layer "F.SilkS")
		)
		(fp_line
			(start -0.12065 -0.305054)
			(end -0.12065 -0.2794)
			(stroke
				(width 0.1)
				(type default)
			)
			(layer "F.Fab")
		)
		(fp_line
			(start -0.67945 -0.305054)
			(end -0.12065 -0.305054)
			(stroke
				(width 0.1)
				(type default)
			)
			(layer "F.Fab")
		)
		(fp_line
			(start 0.67945 -0.3048)
			(end 0.67945 0.3048)
			(stroke
				(width 0.1)
				(type default)
			)
			(layer "F.Fab")
		)
		(fp_line
			(start 0.12065 -0.3048)
			(end 0.67945 -0.3048)
			(stroke
				(width 0.1)
				(type default)
			)
			(layer "F.Fab")
		)
		(fp_line
			(start 0.12065 -0.2794)
			(end 0.12065 -0.3048)
			(stroke
				(width 0.1)
				(type default)
			)
			(layer "F.Fab")
		)
		(fp_line
			(start -0.12065 -0.2794)
			(end 0.12065 -0.2794)
			(stroke
				(width 0.1)
				(type default)
			)
			(layer "F.Fab")
		)
		(fp_line
			(start 0.120396 0.2794)
			(end -0.12065 0.2794)
			(stroke
				(width 0.1)
				(type default)
			)
			(layer "F.Fab")
		)
		(fp_line
			(start -0.12065 0.2794)
			(end -0.12065 0.3048)
			(stroke
				(width 0.1)
				(type default)
			)
			(layer "F.Fab")
		)
		(fp_line
			(start 0.67945 0.3048)
			(end 0.120396 0.3048)
			(stroke
				(width 0.1)
				(type default)
			)
			(layer "F.Fab")
		)
		(fp_line
			(start 0.120396 0.3048)
			(end 0.120396 0.2794)
			(stroke
				(width 0.1)
				(type default)
			)
			(layer "F.Fab")
		)
		(fp_line
			(start -0.12065 0.3048)
			(end -0.67945 0.3048)
			(stroke
				(width 0.1)
				(type default)
			)
			(layer "F.Fab")
		)
		(fp_line
			(start -0.67945 0.3048)
			(end -0.67945 -0.305054)
			(stroke
				(width 0.1)
				(type default)
			)
			(layer "F.Fab")
		)
		(pad "1" smd circle
			(at -0.40005 0 90)
			(size 0 0)
			(layers "F.Cu" "F.Mask" "F.Paste")
			(net "USB_HUB2_TI_VDD33_MRP_PRT_CTL4_GANGPWR")
		)
		(pad "2" smd circle
			(at 0.40005 0 90)
			(size 0 0)
			(layers "F.Cu" "F.Mask" "F.Paste")
			(net "P3V3_AUX_CPU0_USB2_AVDD33")
		)
	)
)
